(kicad_pcb
	(version 20260206)
	(generator "pcbnew")
	(generator_version "10.0")
	(general
		(thickness 1.6)
		(legacy_teardrops no)
	)
	(paper "A4")
	(title_block
		(title "04192023_DAF0TMB3IC0_F0TG_MB_C_brd_V02_OCP.brd")
		(comment 1 "Grand Teton / footprint 3579 of 8354 (J30), pads 1-113 of 291")
	)
	(layers
		(0 "F.Cu" signal "TOP")
		(4 "In1.Cu" signal "GND")
		(6 "In2.Cu" signal "IN1")
		(8 "In3.Cu" signal "GND1")
		(10 "In4.Cu" signal "IN2")
		(12 "In5.Cu" signal "GND2")
		(14 "In6.Cu" signal "IN3")
		(16 "In7.Cu" signal "GND3")
		(18 "In8.Cu" signal "VCC")
		(20 "In9.Cu" signal "VCC1")
		(22 "In10.Cu" signal "GND4")
		(24 "In11.Cu" signal "IN4")
		(26 "In12.Cu" signal "GND5")
		(28 "In13.Cu" signal "IN5")
		(30 "In14.Cu" signal "GND6")
		(32 "In15.Cu" signal "IN6")
		(34 "In16.Cu" signal "GND7")
		(2 "B.Cu" signal "BOTTOM")
		(9 "F.Adhes" user "F.Adhesive")
		(11 "B.Adhes" user "B.Adhesive")
		(13 "F.Paste" user "Package Geometry/Pastemask Top")
		(15 "B.Paste" user "Package Geometry/Pastemask Bottom")
		(5 "F.SilkS" user "Ref Des/Silkscreen Top")
		(7 "B.SilkS" user "Ref Des/Silkscreen Bottom")
		(1 "F.Mask" user "Board Geometry/Soldermask Top")
		(3 "B.Mask" user "Board Geometry/Soldermask Bottom")
		(17 "Dwgs.User" user "User.Drawings")
		(19 "Cmts.User" user "User.Comments")
		(21 "Eco1.User" user "User.Eco1")
		(23 "Eco2.User" user "User.Eco2")
		(25 "Edge.Cuts" user "Board Geometry/Outline")
		(27 "Margin" user)
		(31 "F.CrtYd" user "Package Geometry/Place Bound Top")
		(29 "B.CrtYd" user "Package Geometry/Place Bound Bottom")
		(35 "F.Fab" user "Ref Des/Assembly Top")
		(33 "B.Fab" user "Ref Des/Assembly Bottom")
	)
	(footprint ""
		(layer "F.Cu")
		(at 34.74593 -255.560322 180)
		(property "Reference" "J30"
			(at 3.12293 -81.850992 0)
			(unlocked yes)
			(layer "F.SilkS")
			(effects
				(font
					(size 0.7874 0.5842)
					(thickness 0.1524)
				)
			)
		)
		(property "Value" ""
			(at 0 0 180)
			(layer "F.Fab")
			(effects
				(font
					(size 1.27 1.27)
				)
			)
		)
		(duplicate_pad_numbers_are_jumpers no)
		(pad "1" smd rect
			(at -2.050034 -63.324994 90)
			(size 0.519938 1.4986)
			(layers "F.Cu" "F.Mask" "F.Paste")
			(net "P12V_MEM_CPU1")
		)
		(pad "2" smd rect
			(at -2.050034 -62.47511 90)
			(size 0.519938 1.4986)
			(layers "F.Cu" "F.Mask" "F.Paste")
			(net "Net_2298")
		)
		(pad "3" smd rect
			(at -2.050034 -61.624972 90)
			(size 0.519938 1.4986)
			(layers "F.Cu" "F.Mask" "F.Paste")
			(net "P3V3_AUX")
		)
		(pad "4" smd rect
			(at -2.050034 -60.775088 90)
			(size 0.519938 1.4986)
			(layers "F.Cu" "F.Mask" "F.Paste")
			(net "I3C_SPD_DDRD_CPU1_SCL")
		)
		(pad "5" smd rect
			(at -2.050034 -59.92495 90)
			(size 0.519938 1.4986)
			(layers "F.Cu" "F.Mask" "F.Paste")
			(net "I3C_SPD_DDRD_CPU1_SDA")
		)
		(pad "6" smd rect
			(at -2.050034 -59.075066 90)
			(size 0.519938 1.4986)
			(layers "F.Cu" "F.Mask" "F.Paste")
			(net "GND")
		)
		(pad "7" smd rect
			(at -2.050034 -58.224928 90)
			(size 0.519938 1.4986)
			(layers "F.Cu" "F.Mask" "F.Paste")
			(net "M_D_CPU1_SA_DQ<0>")
		)
		(pad "8" smd rect
			(at -2.050034 -57.375044 90)
			(size 0.519938 1.4986)
			(layers "F.Cu" "F.Mask" "F.Paste")
			(net "GND")
		)
		(pad "9" smd rect
			(at -2.050034 -56.524906 90)
			(size 0.519938 1.4986)
			(layers "F.Cu" "F.Mask" "F.Paste")
			(net "M_D_CPU1_SA_DQ<1>")
		)
		(pad "10" smd rect
			(at -2.050034 -55.675022 90)
			(size 0.519938 1.4986)
			(layers "F.Cu" "F.Mask" "F.Paste")
			(net "GND")
		)
		(pad "11" smd rect
			(at -2.050034 -54.824884 90)
			(size 0.519938 1.4986)
			(layers "F.Cu" "F.Mask" "F.Paste")
			(net "M_D_CPU1_SA_DQS_DP<0>")
		)
		(pad "12" smd rect
			(at -2.050034 -53.975 90)
			(size 0.519938 1.4986)
			(layers "F.Cu" "F.Mask" "F.Paste")
			(net "M_D_CPU1_SA_DQS_DN<0>")
		)
		(pad "13" smd rect
			(at -2.050034 -53.125116 90)
			(size 0.519938 1.4986)
			(layers "F.Cu" "F.Mask" "F.Paste")
			(net "GND")
		)
		(pad "14" smd rect
			(at -2.050034 -52.274978 90)
			(size 0.519938 1.4986)
			(layers "F.Cu" "F.Mask" "F.Paste")
			(net "M_D_CPU1_SA_DQ<4>")
		)
		(pad "15" smd rect
			(at -2.050034 -51.425094 90)
			(size 0.519938 1.4986)
			(layers "F.Cu" "F.Mask" "F.Paste")
			(net "GND")
		)
		(pad "16" smd rect
			(at -2.050034 -50.574956 90)
			(size 0.519938 1.4986)
			(layers "F.Cu" "F.Mask" "F.Paste")
			(net "M_D_CPU1_SA_DQ<5>")
		)
		(pad "17" smd rect
			(at -2.050034 -49.725072 90)
			(size 0.519938 1.4986)
			(layers "F.Cu" "F.Mask" "F.Paste")
			(net "GND")
		)
		(pad "18" smd rect
			(at -2.050034 -48.874934 90)
			(size 0.519938 1.4986)
			(layers "F.Cu" "F.Mask" "F.Paste")
			(net "M_D_CPU1_SA_DQ<8>")
		)
		(pad "19" smd rect
			(at -2.050034 -48.02505 90)
			(size 0.519938 1.4986)
			(layers "F.Cu" "F.Mask" "F.Paste")
			(net "GND")
		)
		(pad "20" smd rect
			(at -2.050034 -47.174912 90)
			(size 0.519938 1.4986)
			(layers "F.Cu" "F.Mask" "F.Paste")
			(net "M_D_CPU1_SA_DQ<9>")
		)
		(pad "21" smd rect
			(at -2.050034 -46.325028 90)
			(size 0.519938 1.4986)
			(layers "F.Cu" "F.Mask" "F.Paste")
			(net "GND")
		)
		(pad "22" smd rect
			(at -2.050034 -45.47489 90)
			(size 0.519938 1.4986)
			(layers "F.Cu" "F.Mask" "F.Paste")
			(net "M_D_CPU1_SA_DQS_DP<1>")
		)
		(pad "23" smd rect
			(at -2.050034 -44.625006 90)
			(size 0.519938 1.4986)
			(layers "F.Cu" "F.Mask" "F.Paste")
			(net "M_D_CPU1_SA_DQS_DN<1>")
		)
		(pad "24" smd rect
			(at -2.050034 -43.775122 90)
			(size 0.519938 1.4986)
			(layers "F.Cu" "F.Mask" "F.Paste")
			(net "GND")
		)
		(pad "25" smd rect
			(at -2.050034 -42.924984 90)
			(size 0.519938 1.4986)
			(layers "F.Cu" "F.Mask" "F.Paste")
			(net "M_D_CPU1_SA_DQ<12>")
		)
		(pad "26" smd rect
			(at -2.050034 -42.0751 90)
			(size 0.519938 1.4986)
			(layers "F.Cu" "F.Mask" "F.Paste")
			(net "GND")
		)
		(pad "27" smd rect
			(at -2.050034 -41.224962 90)
			(size 0.519938 1.4986)
			(layers "F.Cu" "F.Mask" "F.Paste")
			(net "M_D_CPU1_SA_DQ<13>")
		)
		(pad "28" smd rect
			(at -2.050034 -40.375078 90)
			(size 0.519938 1.4986)
			(layers "F.Cu" "F.Mask" "F.Paste")
			(net "GND")
		)
		(pad "29" smd rect
			(at -2.050034 -39.52494 90)
			(size 0.519938 1.4986)
			(layers "F.Cu" "F.Mask" "F.Paste")
			(net "M_D_CPU1_SA_DQ<16>")
		)
		(pad "30" smd rect
			(at -2.050034 -38.675056 90)
			(size 0.519938 1.4986)
			(layers "F.Cu" "F.Mask" "F.Paste")
			(net "GND")
		)
		(pad "31" smd rect
			(at -2.050034 -37.824918 90)
			(size 0.519938 1.4986)
			(layers "F.Cu" "F.Mask" "F.Paste")
			(net "M_D_CPU1_SA_DQ<17>")
		)
		(pad "32" smd rect
			(at -2.050034 -36.975034 90)
			(size 0.519938 1.4986)
			(layers "F.Cu" "F.Mask" "F.Paste")
			(net "GND")
		)
		(pad "33" smd rect
			(at -2.050034 -36.124896 90)
			(size 0.519938 1.4986)
			(layers "F.Cu" "F.Mask" "F.Paste")
			(net "M_D_CPU1_SA_DQS_DP<2>")
		)
		(pad "34" smd rect
			(at -2.050034 -35.275012 90)
			(size 0.519938 1.4986)
			(layers "F.Cu" "F.Mask" "F.Paste")
			(net "M_D_CPU1_SA_DQS_DN<2>")
		)
		(pad "35" smd rect
			(at -2.050034 -34.425128 90)
			(size 0.519938 1.4986)
			(layers "F.Cu" "F.Mask" "F.Paste")
			(net "GND")
		)
		(pad "36" smd rect
			(at -2.050034 -33.57499 90)
			(size 0.519938 1.4986)
			(layers "F.Cu" "F.Mask" "F.Paste")
			(net "M_D_CPU1_SA_DQ<20>")
		)
		(pad "37" smd rect
			(at -2.050034 -32.725106 90)
			(size 0.519938 1.4986)
			(layers "F.Cu" "F.Mask" "F.Paste")
			(net "GND")
		)
		(pad "38" smd rect
			(at -2.050034 -31.874968 90)
			(size 0.519938 1.4986)
			(layers "F.Cu" "F.Mask" "F.Paste")
			(net "M_D_CPU1_SA_DQ<21>")
		)
		(pad "39" smd rect
			(at -2.050034 -31.025084 90)
			(size 0.519938 1.4986)
			(layers "F.Cu" "F.Mask" "F.Paste")
			(net "GND")
		)
		(pad "40" smd rect
			(at -2.050034 -30.174946 90)
			(size 0.519938 1.4986)
			(layers "F.Cu" "F.Mask" "F.Paste")
			(net "M_D_CPU1_SA_DQ<24>")
		)
		(pad "41" smd rect
			(at -2.050034 -29.325062 90)
			(size 0.519938 1.4986)
			(layers "F.Cu" "F.Mask" "F.Paste")
			(net "GND")
		)
		(pad "42" smd rect
			(at -2.050034 -28.474924 90)
			(size 0.519938 1.4986)
			(layers "F.Cu" "F.Mask" "F.Paste")
			(net "M_D_CPU1_SA_DQ<25>")
		)
		(pad "43" smd rect
			(at -2.050034 -27.62504 90)
			(size 0.519938 1.4986)
			(layers "F.Cu" "F.Mask" "F.Paste")
			(net "GND")
		)
		(pad "44" smd rect
			(at -2.050034 -26.774902 90)
			(size 0.519938 1.4986)
			(layers "F.Cu" "F.Mask" "F.Paste")
			(net "M_D_CPU1_SA_DQS_DP<3>")
		)
		(pad "45" smd rect
			(at -2.050034 -25.925018 90)
			(size 0.519938 1.4986)
			(layers "F.Cu" "F.Mask" "F.Paste")
			(net "M_D_CPU1_SA_DQS_DN<3>")
		)
		(pad "46" smd rect
			(at -2.050034 -25.07488 90)
			(size 0.519938 1.4986)
			(layers "F.Cu" "F.Mask" "F.Paste")
			(net "GND")
		)
		(pad "47" smd rect
			(at -2.050034 -24.224996 90)
			(size 0.519938 1.4986)
			(layers "F.Cu" "F.Mask" "F.Paste")
			(net "M_D_CPU1_SA_DQ<28>")
		)
		(pad "48" smd rect
			(at -2.050034 -23.375112 90)
			(size 0.519938 1.4986)
			(layers "F.Cu" "F.Mask" "F.Paste")
			(net "GND")
		)
		(pad "49" smd rect
			(at -2.050034 -22.524974 90)
			(size 0.519938 1.4986)
			(layers "F.Cu" "F.Mask" "F.Paste")
			(net "M_D_CPU1_SA_DQ<29>")
		)
		(pad "50" smd rect
			(at -2.050034 -21.67509 90)
			(size 0.519938 1.4986)
			(layers "F.Cu" "F.Mask" "F.Paste")
			(net "GND")
		)
		(pad "51" smd rect
			(at -2.050034 -20.824952 90)
			(size 0.519938 1.4986)
			(layers "F.Cu" "F.Mask" "F.Paste")
			(net "M_D_CPU1_SA_CB<0>")
		)
		(pad "52" smd rect
			(at -2.050034 -19.975068 90)
			(size 0.519938 1.4986)
			(layers "F.Cu" "F.Mask" "F.Paste")
			(net "GND")
		)
		(pad "53" smd rect
			(at -2.050034 -19.12493 90)
			(size 0.519938 1.4986)
			(layers "F.Cu" "F.Mask" "F.Paste")
			(net "M_D_CPU1_SA_CB<1>")
		)
		(pad "54" smd rect
			(at -2.050034 -18.275046 90)
			(size 0.519938 1.4986)
			(layers "F.Cu" "F.Mask" "F.Paste")
			(net "GND")
		)
		(pad "55" smd rect
			(at -2.050034 -17.424908 90)
			(size 0.519938 1.4986)
			(layers "F.Cu" "F.Mask" "F.Paste")
			(net "M_D_CPU1_SA_DQS_DP<4>")
		)
		(pad "56" smd rect
			(at -2.050034 -16.575024 90)
			(size 0.519938 1.4986)
			(layers "F.Cu" "F.Mask" "F.Paste")
			(net "M_D_CPU1_SA_DQS_DN<4>")
		)
		(pad "57" smd rect
			(at -2.050034 -15.724886 90)
			(size 0.519938 1.4986)
			(layers "F.Cu" "F.Mask" "F.Paste")
			(net "GND")
		)
		(pad "58" smd rect
			(at -2.050034 -14.875002 90)
			(size 0.519938 1.4986)
			(layers "F.Cu" "F.Mask" "F.Paste")
			(net "M_D_CPU1_SA_CB<4>")
		)
		(pad "59" smd rect
			(at -2.050034 -14.025118 90)
			(size 0.519938 1.4986)
			(layers "F.Cu" "F.Mask" "F.Paste")
			(net "GND")
		)
		(pad "60" smd rect
			(at -2.050034 -13.17498 90)
			(size 0.519938 1.4986)
			(layers "F.Cu" "F.Mask" "F.Paste")
			(net "M_D_CPU1_SA_CB<5>")
		)
		(pad "61" smd rect
			(at -2.050034 -12.325096 90)
			(size 0.519938 1.4986)
			(layers "F.Cu" "F.Mask" "F.Paste")
			(net "GND")
		)
		(pad "62" smd rect
			(at -2.050034 -11.474958 90)
			(size 0.519938 1.4986)
			(layers "F.Cu" "F.Mask" "F.Paste")
			(net "M_D_CPU1_ALERT_N")
		)
		(pad "63" smd rect
			(at -2.050034 -10.625074 90)
			(size 0.519938 1.4986)
			(layers "F.Cu" "F.Mask" "F.Paste")
			(net "GND")
		)
		(pad "64" smd rect
			(at -2.050034 -9.774936 90)
			(size 0.519938 1.4986)
			(layers "F.Cu" "F.Mask" "F.Paste")
			(net "M_D_CPU1_SA_CS_N<0>")
		)
		(pad "65" smd rect
			(at -2.050034 -8.925052 90)
			(size 0.519938 1.4986)
			(layers "F.Cu" "F.Mask" "F.Paste")
			(net "GND")
		)
		(pad "66" smd rect
			(at -2.050034 -8.074914 90)
			(size 0.519938 1.4986)
			(layers "F.Cu" "F.Mask" "F.Paste")
			(net "M_D_CPU1_SA_CA<0>")
		)
		(pad "67" smd rect
			(at -2.050034 -7.22503 90)
			(size 0.519938 1.4986)
			(layers "F.Cu" "F.Mask" "F.Paste")
			(net "GND")
		)
		(pad "68" smd rect
			(at -2.050034 -6.374892 90)
			(size 0.519938 1.4986)
			(layers "F.Cu" "F.Mask" "F.Paste")
			(net "M_D_CPU1_SA_CA<2>")
		)
		(pad "69" smd rect
			(at -2.050034 -5.525008 90)
			(size 0.519938 1.4986)
			(layers "F.Cu" "F.Mask" "F.Paste")
			(net "GND")
		)
		(pad "70" smd rect
			(at -2.050034 -4.675124 90)
			(size 0.519938 1.4986)
			(layers "F.Cu" "F.Mask" "F.Paste")
			(net "M_D_CPU1_SA_CA<4>")
		)
		(pad "71" smd rect
			(at -2.050034 -3.824986 90)
			(size 0.519938 1.4986)
			(layers "F.Cu" "F.Mask" "F.Paste")
			(net "GND")
		)
		(pad "72" smd rect
			(at -2.050034 -2.975102 90)
			(size 0.519938 1.4986)
			(layers "F.Cu" "F.Mask" "F.Paste")
			(net "M_D_CPU1_SA_CA<6>")
		)
		(pad "73" smd rect
			(at -2.050034 -2.124964 90)
			(size 0.519938 1.4986)
			(layers "F.Cu" "F.Mask" "F.Paste")
			(net "GND")
		)
		(pad "74" smd rect
			(at -2.050034 -1.27508 90)
			(size 0.519938 1.4986)
			(layers "F.Cu" "F.Mask" "F.Paste")
			(net "M_D_CPU1_SA_PAR")
		)
		(pad "75" smd rect
			(at -2.050034 -0.424942 90)
			(size 0.519938 1.4986)
			(layers "F.Cu" "F.Mask" "F.Paste")
			(net "GND")
		)
		(pad "76" smd rect
			(at -2.050034 5.525008 90)
			(size 0.519938 1.4986)
			(layers "F.Cu" "F.Mask" "F.Paste")
			(net "M_D_CPU1_SB_CA<0>")
		)
		(pad "77" smd rect
			(at -2.050034 6.374892 90)
			(size 0.519938 1.4986)
			(layers "F.Cu" "F.Mask" "F.Paste")
			(net "GND")
		)
		(pad "78" smd rect
			(at -2.050034 7.22503 90)
			(size 0.519938 1.4986)
			(layers "F.Cu" "F.Mask" "F.Paste")
			(net "M_D_CPU1_SB_CA<2>")
		)
		(pad "79" smd rect
			(at -2.050034 8.074914 90)
			(size 0.519938 1.4986)
			(layers "F.Cu" "F.Mask" "F.Paste")
			(net "GND")
		)
		(pad "80" smd rect
			(at -2.050034 8.925052 90)
			(size 0.519938 1.4986)
			(layers "F.Cu" "F.Mask" "F.Paste")
			(net "M_D_CPU1_SB_CA<4>")
		)
		(pad "81" smd rect
			(at -2.050034 9.774936 90)
			(size 0.519938 1.4986)
			(layers "F.Cu" "F.Mask" "F.Paste")
			(net "GND")
		)
		(pad "82" smd rect
			(at -2.050034 10.625074 90)
			(size 0.519938 1.4986)
			(layers "F.Cu" "F.Mask" "F.Paste")
			(net "M_D_CPU1_SB_CA<6>")
		)
		(pad "83" smd rect
			(at -2.050034 11.474958 90)
			(size 0.519938 1.4986)
			(layers "F.Cu" "F.Mask" "F.Paste")
			(net "GND")
		)
		(pad "84" smd rect
			(at -2.050034 12.325096 90)
			(size 0.519938 1.4986)
			(layers "F.Cu" "F.Mask" "F.Paste")
			(net "M_D_CPU1_SB_CS_N<0>")
		)
		(pad "85" smd rect
			(at -2.050034 13.17498 90)
			(size 0.519938 1.4986)
			(layers "F.Cu" "F.Mask" "F.Paste")
			(net "GND")
		)
		(pad "86" smd rect
			(at -2.050034 14.025118 90)
			(size 0.519938 1.4986)
			(layers "F.Cu" "F.Mask" "F.Paste")
			(net "M_D_CPU1_SA_RSP<0>")
		)
		(pad "87" smd rect
			(at -2.050034 14.875002 90)
			(size 0.519938 1.4986)
			(layers "F.Cu" "F.Mask" "F.Paste")
			(net "M_D_CPU1_SB_RSP<0>")
		)
		(pad "88" smd rect
			(at -2.050034 15.724886 90)
			(size 0.519938 1.4986)
			(layers "F.Cu" "F.Mask" "F.Paste")
			(net "GND")
		)
		(pad "89" smd rect
			(at -2.050034 16.575024 90)
			(size 0.519938 1.4986)
			(layers "F.Cu" "F.Mask" "F.Paste")
			(net "M_D_CPU1_SB_CB<4>")
		)
		(pad "90" smd rect
			(at -2.050034 17.424908 90)
			(size 0.519938 1.4986)
			(layers "F.Cu" "F.Mask" "F.Paste")
			(net "GND")
		)
		(pad "91" smd rect
			(at -2.050034 18.275046 90)
			(size 0.519938 1.4986)
			(layers "F.Cu" "F.Mask" "F.Paste")
			(net "M_D_CPU1_SB_CB<5>")
		)
		(pad "92" smd rect
			(at -2.050034 19.12493 90)
			(size 0.519938 1.4986)
			(layers "F.Cu" "F.Mask" "F.Paste")
			(net "GND")
		)
		(pad "93" smd rect
			(at -2.050034 19.975068 90)
			(size 0.519938 1.4986)
			(layers "F.Cu" "F.Mask" "F.Paste")
			(net "M_D_CPU1_SB_DQS_DP<9>")
		)
		(pad "94" smd rect
			(at -2.050034 20.824952 90)
			(size 0.519938 1.4986)
			(layers "F.Cu" "F.Mask" "F.Paste")
			(net "M_D_CPU1_SB_DQS_DN<9>")
		)
		(pad "95" smd rect
			(at -2.050034 21.67509 90)
			(size 0.519938 1.4986)
			(layers "F.Cu" "F.Mask" "F.Paste")
			(net "GND")
		)
		(pad "96" smd rect
			(at -2.050034 22.524974 90)
			(size 0.519938 1.4986)
			(layers "F.Cu" "F.Mask" "F.Paste")
			(net "M_D_CPU1_SB_CB<0>")
		)
		(pad "97" smd rect
			(at -2.050034 23.375112 90)
			(size 0.519938 1.4986)
			(layers "F.Cu" "F.Mask" "F.Paste")
			(net "GND")
		)
		(pad "98" smd rect
			(at -2.050034 24.224996 90)
			(size 0.519938 1.4986)
			(layers "F.Cu" "F.Mask" "F.Paste")
			(net "M_D_CPU1_SB_CB<1>")
		)
		(pad "99" smd rect
			(at -2.050034 25.07488 90)
			(size 0.519938 1.4986)
			(layers "F.Cu" "F.Mask" "F.Paste")
			(net "GND")
		)
		(pad "100" smd rect
			(at -2.050034 25.925018 90)
			(size 0.519938 1.4986)
			(layers "F.Cu" "F.Mask" "F.Paste")
			(net "M_D_CPU1_SB_DQ<0>")
		)
		(pad "101" smd rect
			(at -2.050034 26.774902 90)
			(size 0.519938 1.4986)
			(layers "F.Cu" "F.Mask" "F.Paste")
			(net "GND")
		)
		(pad "102" smd rect
			(at -2.050034 27.62504 90)
			(size 0.519938 1.4986)
			(layers "F.Cu" "F.Mask" "F.Paste")
			(net "M_D_CPU1_SB_DQ<1>")
		)
		(pad "103" smd rect
			(at -2.050034 28.474924 90)
			(size 0.519938 1.4986)
			(layers "F.Cu" "F.Mask" "F.Paste")
			(net "GND")
		)
		(pad "104" smd rect
			(at -2.050034 29.325062 90)
			(size 0.519938 1.4986)
			(layers "F.Cu" "F.Mask" "F.Paste")
			(net "M_D_CPU1_SB_DQS_DP<0>")
		)
		(pad "105" smd rect
			(at -2.050034 30.174946 90)
			(size 0.519938 1.4986)
			(layers "F.Cu" "F.Mask" "F.Paste")
			(net "M_D_CPU1_SB_DQS_DN<0>")
		)
		(pad "106" smd rect
			(at -2.050034 31.025084 90)
			(size 0.519938 1.4986)
			(layers "F.Cu" "F.Mask" "F.Paste")
			(net "GND")
		)
		(pad "107" smd rect
			(at -2.050034 31.874968 90)
			(size 0.519938 1.4986)
			(layers "F.Cu" "F.Mask" "F.Paste")
			(net "M_D_CPU1_SB_DQ<4>")
		)
		(pad "108" smd rect
			(at -2.050034 32.725106 90)
			(size 0.519938 1.4986)
			(layers "F.Cu" "F.Mask" "F.Paste")
			(net "GND")
		)
		(pad "109" smd rect
			(at -2.050034 33.57499 90)
			(size 0.519938 1.4986)
			(layers "F.Cu" "F.Mask" "F.Paste")
			(net "M_D_CPU1_SB_DQ<5>")
		)
		(pad "110" smd rect
			(at -2.050034 34.425128 90)
			(size 0.519938 1.4986)
			(layers "F.Cu" "F.Mask" "F.Paste")
			(net "GND")
		)
		(pad "111" smd rect
			(at -2.050034 35.275012 90)
			(size 0.519938 1.4986)
			(layers "F.Cu" "F.Mask" "F.Paste")
			(net "M_D_CPU1_SB_DQ<8>")
		)
		(pad "112" smd rect
			(at -2.050034 36.124896 90)
			(size 0.519938 1.4986)
			(layers "F.Cu" "F.Mask" "F.Paste")
			(net "GND")
		)
		(pad "113" smd rect
			(at -2.050034 36.975034 90)
			(size 0.519938 1.4986)
			(layers "F.Cu" "F.Mask" "F.Paste")
			(net "M_D_CPU1_SB_DQ<9>")
		)
	)
)
